# T6G (Grand Teton) — schematic netlist excerpt (pin names and nets, part order shuffled) for the footprints in the layout excerpt that follows; sources: Cadence DE-HDL packaged netlist, KiCad conversion of 04192023_DAF0TMB3IC0_F0TG_MB_C_brd_V02_OCP.brd

PR209  Q_RES  5.6 1% CHIP  pkg 0402LF  page 215 : A = SW_PVDDCR_SOC_P1_BOOT1 ; B = SW_PVDDCR_SOC_P1_BOOT1_RC
R2473  Q_RES  0 5% CHIP  pkg 0402LF  page 132 : A = FB_BMC_ISOLATE_R1 ; B = FB_BMC_ISOLATE

(kicad_pcb
	(version 20260206)
	(generator "pcbnew")
	(generator_version "10.0")
	(general
		(thickness 1.6)
		(legacy_teardrops no)
	)
	(paper "A4")
	(title_block
		(title "04192023_DAF0TMB3IC0_F0TG_MB_C_brd_V02_OCP.brd")
		(comment 1 "Grand Teton / footprints 2453-2454 of 8354")
	)
	(layers
		(0 "F.Cu" signal "TOP")
		(4 "In1.Cu" signal "GND")
		(6 "In2.Cu" signal "IN1")
		(8 "In3.Cu" signal "GND1")
		(10 "In4.Cu" signal "IN2")
		(12 "In5.Cu" signal "GND2")
		(14 "In6.Cu" signal "IN3")
		(16 "In7.Cu" signal "GND3")
		(18 "In8.Cu" signal "VCC")
		(20 "In9.Cu" signal "VCC1")
		(22 "In10.Cu" signal "GND4")
		(24 "In11.Cu" signal "IN4")
		(26 "In12.Cu" signal "GND5")
		(28 "In13.Cu" signal "IN5")
		(30 "In14.Cu" signal "GND6")
		(32 "In15.Cu" signal "IN6")
		(34 "In16.Cu" signal "GND7")
		(2 "B.Cu" signal "BOTTOM")
		(9 "F.Adhes" user "F.Adhesive")
		(11 "B.Adhes" user "B.Adhesive")
		(13 "F.Paste" user "Package Geometry/Pastemask Top")
		(15 "B.Paste" user "Package Geometry/Pastemask Bottom")
		(5 "F.SilkS" user "Ref Des/Silkscreen Top")
		(7 "B.SilkS" user "Ref Des/Silkscreen Bottom")
		(1 "F.Mask" user "Board Geometry/Soldermask Top")
		(3 "B.Mask" user "Board Geometry/Soldermask Bottom")
		(17 "Dwgs.User" user "User.Drawings")
		(19 "Cmts.User" user "User.Comments")
		(21 "Eco1.User" user "User.Eco1")
		(23 "Eco2.User" user "User.Eco2")
		(25 "Edge.Cuts" user "Board Geometry/Outline")
		(27 "Margin" user)
		(31 "F.CrtYd" user "Package Geometry/Place Bound Top")
		(29 "B.CrtYd" user "Package Geometry/Place Bound Bottom")
		(35 "F.Fab" user "Ref Des/Assembly Top")
		(33 "B.Fab" user "Ref Des/Assembly Bottom")
	)
	(footprint ""
		(layer "F.Cu")
		(at 463.465926 -97.523808)
		(property "Reference" "R2473"
			(at 0 0 0)
			(layer "F.SilkS")
			(hide yes)
			(effects
				(font
					(size 1.27 1.27)
				)
			)
		)
		(property "Value" ""
			(at 0 0 0)
			(layer "F.Fab")
			(effects
				(font
					(size 1.27 1.27)
				)
			)
		)
		(duplicate_pad_numbers_are_jumpers no)
		(fp_line
			(start -0.7874 -0.4064)
			(end 0.7874 -0.4064)
			(stroke
				(width 0.1524)
				(type default)
			)
			(layer "F.SilkS")
		)
		(fp_line
			(start -0.7874 0.4064)
			(end -0.7874 -0.4064)
			(stroke
				(width 0.1524)
				(type default)
			)
			(layer "F.SilkS")
		)
		(fp_line
			(start 0.7874 -0.4064)
			(end 0.7874 0.4064)
			(stroke
				(width 0.1524)
				(type default)
			)
			(layer "F.SilkS")
		)
		(fp_line
			(start 0.7874 0.4064)
			(end -0.7874 0.4064)
			(stroke
				(width 0.1524)
				(type default)
			)
			(layer "F.SilkS")
		)
		(fp_line
			(start -0.67945 -0.305054)
			(end -0.12065 -0.305054)
			(stroke
				(width 0.1)
				(type default)
			)
			(layer "F.Fab")
		)
		(fp_line
			(start -0.67945 0.3048)
			(end -0.67945 -0.305054)
			(stroke
				(width 0.1)
				(type default)
			)
			(layer "F.Fab")
		)
		(fp_line
			(start -0.12065 -0.305054)
			(end -0.12065 -0.2794)
			(stroke
				(width 0.1)
				(type default)
			)
			(layer "F.Fab")
		)
		(fp_line
			(start -0.12065 -0.2794)
			(end 0.12065 -0.2794)
			(stroke
				(width 0.1)
				(type default)
			)
			(layer "F.Fab")
		)
		(fp_line
			(start -0.12065 0.2794)
			(end -0.12065 0.3048)
			(stroke
				(width 0.1)
				(type default)
			)
			(layer "F.Fab")
		)
		(fp_line
			(start -0.12065 0.3048)
			(end -0.67945 0.3048)
			(stroke
				(width 0.1)
				(type default)
			)
			(layer "F.Fab")
		)
		(fp_line
			(start 0.120396 0.2794)
			(end -0.12065 0.2794)
			(stroke
				(width 0.1)
				(type default)
			)
			(layer "F.Fab")
		)
		(fp_line
			(start 0.120396 0.3048)
			(end 0.120396 0.2794)
			(stroke
				(width 0.1)
				(type default)
			)
			(layer "F.Fab")
		)
		(fp_line
			(start 0.12065 -0.3048)
			(end 0.67945 -0.3048)
			(stroke
				(width 0.1)
				(type default)
			)
			(layer "F.Fab")
		)
		(fp_line
			(start 0.12065 -0.2794)
			(end 0.12065 -0.3048)
			(stroke
				(width 0.1)
				(type default)
			)
			(layer "F.Fab")
		)
		(fp_line
			(start 0.67945 -0.3048)
			(end 0.67945 0.3048)
			(stroke
				(width 0.1)
				(type default)
			)
			(layer "F.Fab")
		)
		(fp_line
			(start 0.67945 0.3048)
			(end 0.120396 0.3048)
			(stroke
				(width 0.1)
				(type default)
			)
			(layer "F.Fab")
		)
		(pad "1" smd circle
			(at -0.40005 0)
			(size 0 0)
			(layers "F.Cu" "F.Mask" "F.Paste")
			(net "FB_BMC_ISOLATE_R1")
		)
		(pad "2" smd circle
			(at 0.40005 0)
			(size 0 0)
			(layers "F.Cu" "F.Mask" "F.Paste")
			(net "FB_BMC_ISOLATE")
		)
	)
	(footprint ""
		(layer "F.Cu")
		(at 114.926364 -167.2717 -90)
		(property "Reference" "PR209"
			(at 0 0 270)
			(layer "F.SilkS")
			(hide yes)
			(effects
				(font
					(size 1.27 1.27)
				)
			)
		)
		(property "Value" ""
			(at 0 0 270)
			(layer "F.Fab")
			(effects
				(font
					(size 1.27 1.27)
				)
			)
		)
		(duplicate_pad_numbers_are_jumpers no)
		(fp_line
			(start -0.7874 0.4064)
			(end -0.7874 -0.4064)
			(stroke
				(width 0.1524)
				(type default)
			)
			(layer "F.SilkS")
		)
		(fp_line
			(start 0.7874 0.4064)
			(end -0.7874 0.4064)
			(stroke
				(width 0.1524)
				(type default)
			)
			(layer "F.SilkS")
		)
		(fp_line
			(start -0.7874 -0.4064)
			(end 0.7874 -0.4064)
			(stroke
				(width 0.1524)
				(type default)
			)
			(layer "F.SilkS")
		)
		(fp_line
			(start 0.7874 -0.4064)
			(end 0.7874 0.4064)
			(stroke
				(width 0.1524)
				(type default)
			)
			(layer "F.SilkS")
		)
		(fp_line
			(start -0.67945 0.3048)
			(end -0.67945 -0.305054)
			(stroke
				(width 0.1)
				(type default)
			)
			(layer "F.Fab")
		)
		(fp_line
			(start -0.12065 0.3048)
			(end -0.67945 0.3048)
			(stroke
				(width 0.1)
				(type default)
			)
			(layer "F.Fab")
		)
		(fp_line
			(start 0.120396 0.3048)
			(end 0.120396 0.2794)
			(stroke
				(width 0.1)
				(type default)
			)
			(layer "F.Fab")
		)
		(fp_line
			(start 0.67945 0.3048)
			(end 0.120396 0.3048)
			(stroke
				(width 0.1)
				(type default)
			)
			(layer "F.Fab")
		)
		(fp_line
			(start -0.12065 0.2794)
			(end -0.12065 0.3048)
			(stroke
				(width 0.1)
				(type default)
			)
			(layer "F.Fab")
		)
		(fp_line
			(start 0.120396 0.2794)
			(end -0.12065 0.2794)
			(stroke
				(width 0.1)
				(type default)
			)
			(layer "F.Fab")
		)
		(fp_line
			(start -0.12065 -0.2794)
			(end 0.12065 -0.2794)
			(stroke
				(width 0.1)
				(type default)
			)
			(layer "F.Fab")
		)
		(fp_line
			(start 0.12065 -0.2794)
			(end 0.12065 -0.3048)
			(stroke
				(width 0.1)
				(type default)
			)
			(layer "F.Fab")
		)
		(fp_line
			(start 0.12065 -0.3048)
			(end 0.67945 -0.3048)
			(stroke
				(width 0.1)
				(type default)
			)
			(layer "F.Fab")
		)
		(fp_line
			(start 0.67945 -0.3048)
			(end 0.67945 0.3048)
			(stroke
				(width 0.1)
				(type default)
			)
			(layer "F.Fab")
		)
		(fp_line
			(start -0.67945 -0.305054)
			(end -0.12065 -0.305054)
			(stroke
				(width 0.1)
				(type default)
			)
			(layer "F.Fab")
		)
		(fp_line
			(start -0.12065 -0.305054)
			(end -0.12065 -0.2794)
			(stroke
				(width 0.1)
				(type default)
			)
			(layer "F.Fab")
		)
		(pad "1" smd circle
			(at -0.40005 0 270)
			(size 0 0)
			(layers "F.Cu" "F.Mask" "F.Paste")
			(net "SW_PVDDCR_SOC_P1_BOOT1")
		)
		(pad "2" smd circle
			(at 0.40005 0 270)
			(size 0 0)
			(layers "F.Cu" "F.Mask" "F.Paste")
			(net "SW_PVDDCR_SOC_P1_BOOT1_RC")
		)
	)
)
